G04*
G04 #@! TF.GenerationSoftware,Altium Limited,Altium Designer,23.0.1 (38)*
G04*
G04 Layer_Color=16711935*
%FSLAX25Y25*%
%MOIN*%
G70*
G04*
G04 #@! TF.SameCoordinates,C48E81DB-6E20-4E2D-80E6-7C5AFAA1A21F*
G04*
G04*
G04 #@! TF.FilePolarity,Positive*
G04*
G01*
G75*
M02*
